(kicad_pcb
	(version 20260206)
	(generator "pcbnew")
	(generator_version "10.0")
	(general
		(thickness 1.6)
		(legacy_teardrops no)
	)
	(paper "A4")
	(title_block
		(title "peb — Lightning_PEB_BRD.brd")
		(comment 1 "Lightning (Wiwynn / Facebook NVMe JBOF) / footprints 899-906 of 2563")
	)
	(layers
		(0 "F.Cu" signal "TOP")
		(4 "In1.Cu" signal "L2GND")
		(6 "In2.Cu" signal "L3")
		(8 "In3.Cu" signal "L4VCC")
		(10 "In4.Cu" signal "L5VCC")
		(12 "In5.Cu" signal "L6")
		(14 "In6.Cu" signal "L7GND")
		(2 "B.Cu" signal "BOTTOM")
		(9 "F.Adhes" user "F.Adhesive")
		(11 "B.Adhes" user "B.Adhesive")
		(13 "F.Paste" user "Package Geometry/Pastemask Top")
		(15 "B.Paste" user "Package Geometry/Pastemask Bottom")
		(5 "F.SilkS" user "Ref Des/Silkscreen Top")
		(7 "B.SilkS" user "Ref Des/Silkscreen Bottom")
		(1 "F.Mask" user "Board Geometry/Soldermask Top")
		(3 "B.Mask" user "Board Geometry/Soldermask Bottom")
		(17 "Dwgs.User" user "User.Drawings")
		(19 "Cmts.User" user "User.Comments")
		(21 "Eco1.User" user "User.Eco1")
		(23 "Eco2.User" user "User.Eco2")
		(25 "Edge.Cuts" user "Board Geometry/Outline")
		(27 "Margin" user)
		(31 "F.CrtYd" user "Package Geometry/Place Bound Top")
		(29 "B.CrtYd" user "Package Geometry/Place Bound Bottom")
		(35 "F.Fab" user "Ref Des/Assembly Top")
		(33 "B.Fab" user "Ref Des/Assembly Bottom")
	)
	(footprint ""
		(layer "F.Cu")
		(at 137.586974 -74.365104)
		(property "Reference" "R615"
			(at 0 0 0)
			(layer "F.SilkS")
			(hide yes)
			(effects
				(font
					(size 1.27 1.27)
				)
			)
		)
		(property "Value" "100KR2F-L1-GP"
			(at 0.064008 -3.993896 0)
			(unlocked yes)
			(layer "F.Fab")
			(hide yes)
			(effects
				(font
					(size 1.016 1.016)
					(thickness 0.1524)
				)
			)
		)
		(property "Device Type" "R402H16"
			(at 0.064008 -5.517896 0)
			(unlocked yes)
			(layer "F.Fab")
			(hide yes)
			(effects
				(font
					(size 1.016 1.016)
					(thickness 0.1524)
				)
			)
		)
		(duplicate_pad_numbers_are_jumpers no)
		(fp_line
			(start -0.508 -0.9398)
			(end -0.508 0.9398)
			(stroke
				(width 0.1524)
				(type default)
			)
			(layer "F.SilkS")
		)
		(fp_line
			(start 0.508 -0.9398)
			(end -0.508 -0.9398)
			(stroke
				(width 0.1524)
				(type default)
			)
			(layer "F.SilkS")
		)
		(fp_rect
			(start -0.508 0.9398)
			(end 0.508 -0.9398)
			(stroke
				(width 0)
				(type default)
			)
			(fill no)
			(layer "F.CrtYd")
		)
		(fp_rect
			(start -0.508 0.9398)
			(end 0.508 -0.9398)
			(stroke
				(width 0)
				(type default)
			)
			(fill no)
			(layer "F.Fab")
		)
		(pad "1" smd custom
			(at 0 -0.4445)
			(size 0.1397 0.1397)
			(layers "F.Cu" "F.Mask" "F.Paste")
			(net "DUT_VDDO")
			(options
				(clearance outline)
				(anchor circle)
			)
			(primitives
				(gr_poly
					(pts
						(arc
							(start -0.1778 -0.2794)
							(mid -0.249642 -0.249642)
							(end -0.2794 -0.1778)
						)
						(arc
							(start -0.2794 0.1778)
							(mid -0.249642 0.249642)
							(end -0.1778 0.2794)
						)
						(arc
							(start 0.1778 0.2794)
							(mid 0.249642 0.249642)
							(end 0.2794 0.1778)
						)
						(arc
							(start 0.2794 -0.1778)
							(mid 0.249642 -0.249642)
							(end 0.1778 -0.2794)
						)
					)
					(width 0)
					(fill yes)
				)
			)
		)
		(pad "2" smd custom
			(at 0 0.4445)
			(size 0.1397 0.1397)
			(layers "F.Cu" "F.Mask" "F.Paste")
			(net "SPI_DATA0_0_R")
			(options
				(clearance outline)
				(anchor circle)
			)
			(primitives
				(gr_poly
					(pts
						(arc
							(start -0.1778 -0.2794)
							(mid -0.249642 -0.249642)
							(end -0.2794 -0.1778)
						)
						(arc
							(start -0.2794 0.1778)
							(mid -0.249642 0.249642)
							(end -0.1778 0.2794)
						)
						(arc
							(start 0.1778 0.2794)
							(mid 0.249642 0.249642)
							(end 0.2794 0.1778)
						)
						(arc
							(start 0.2794 -0.1778)
							(mid 0.249642 -0.249642)
							(end 0.1778 -0.2794)
						)
					)
					(width 0)
					(fill yes)
				)
			)
		)
	)
	(footprint ""
		(layer "F.Cu")
		(at 30.65272 -118.36908)
		(property "Reference" "TP305"
			(at 0 0 0)
			(layer "F.SilkS")
			(hide yes)
			(effects
				(font
					(size 1.27 1.27)
				)
			)
		)
		(property "Value" "TPAD28-2-GP"
			(at -0.0127 -1.6637 0)
			(unlocked yes)
			(layer "F.Fab")
			(hide yes)
			(effects
				(font
					(size 1.016 1.016)
					(thickness 0.1524)
				)
			)
		)
		(property "Device Type" "TPAD28"
			(at -0.0127 -3.1877 0)
			(unlocked yes)
			(layer "F.Fab")
			(hide yes)
			(effects
				(font
					(size 1.016 1.016)
					(thickness 0.1524)
				)
			)
		)
		(duplicate_pad_numbers_are_jumpers no)
		(fp_poly
			(pts
				(arc
					(start 0.3556 0)
					(mid -0.3556 0)
					(end 0.3556 0)
				)
			)
			(stroke
				(width 0)
				(type default)
			)
			(fill no)
			(layer "F.CrtYd")
		)
		(fp_poly
			(pts
				(arc
					(start 0.6096 0)
					(mid -0.6096 0)
					(end 0.6096 0)
				)
			)
			(stroke
				(width 0)
				(type default)
			)
			(fill no)
			(layer "F.Fab")
		)
		(pad "1" smd circle
			(at 0 0)
			(size 0.7112 0.7112)
			(layers "F.Cu" "F.Mask" "F.Paste")
			(net "TP_GPIOD0")
		)
	)
	(footprint ""
		(layer "F.Cu")
		(at 12.446 -120.65)
		(property "Reference" "R16"
			(at 0 0 0)
			(layer "F.SilkS")
			(hide yes)
			(effects
				(font
					(size 1.27 1.27)
				)
			)
		)
		(property "Value" "0R2J-2-GP"
			(at 0.064008 -3.993896 0)
			(unlocked yes)
			(layer "F.Fab")
			(hide yes)
			(effects
				(font
					(size 1.016 1.016)
					(thickness 0.1524)
				)
			)
		)
		(property "Device Type" "R402H16"
			(at 0.064008 -5.517896 0)
			(unlocked yes)
			(layer "F.Fab")
			(hide yes)
			(effects
				(font
					(size 1.016 1.016)
					(thickness 0.1524)
				)
			)
		)
		(duplicate_pad_numbers_are_jumpers no)
		(fp_line
			(start -0.508 -0.9398)
			(end -0.508 0.9398)
			(stroke
				(width 0.1524)
				(type default)
			)
			(layer "F.SilkS")
		)
		(fp_line
			(start 0.508 -0.9398)
			(end -0.508 -0.9398)
			(stroke
				(width 0.1524)
				(type default)
			)
			(layer "F.SilkS")
		)
		(fp_rect
			(start -0.508 0.9398)
			(end 0.508 -0.9398)
			(stroke
				(width 0)
				(type default)
			)
			(fill no)
			(layer "F.CrtYd")
		)
		(fp_rect
			(start -0.508 0.9398)
			(end 0.508 -0.9398)
			(stroke
				(width 0)
				(type default)
			)
			(fill no)
			(layer "F.Fab")
		)
		(pad "1" smd custom
			(at 0 -0.4445)
			(size 0.1397 0.1397)
			(layers "F.Cu" "F.Mask" "F.Paste")
			(net "BMC_I2C1_MINI1_SCL_S")
			(options
				(clearance outline)
				(anchor circle)
			)
			(primitives
				(gr_poly
					(pts
						(arc
							(start -0.1778 -0.2794)
							(mid -0.249642 -0.249642)
							(end -0.2794 -0.1778)
						)
						(arc
							(start -0.2794 0.1778)
							(mid -0.249642 0.249642)
							(end -0.1778 0.2794)
						)
						(arc
							(start 0.1778 0.2794)
							(mid 0.249642 0.249642)
							(end 0.2794 0.1778)
						)
						(arc
							(start 0.2794 -0.1778)
							(mid 0.249642 -0.249642)
							(end 0.1778 -0.2794)
						)
					)
					(width 0)
					(fill yes)
				)
			)
		)
		(pad "2" smd custom
			(at 0 0.4445)
			(size 0.1397 0.1397)
			(layers "F.Cu" "F.Mask" "F.Paste")
			(net "BMC_I2C1_MINI1_SCL")
			(options
				(clearance outline)
				(anchor circle)
			)
			(primitives
				(gr_poly
					(pts
						(arc
							(start -0.1778 -0.2794)
							(mid -0.249642 -0.249642)
							(end -0.2794 -0.1778)
						)
						(arc
							(start -0.2794 0.1778)
							(mid -0.249642 0.249642)
							(end -0.1778 0.2794)
						)
						(arc
							(start 0.1778 0.2794)
							(mid 0.249642 0.249642)
							(end 0.2794 0.1778)
						)
						(arc
							(start 0.2794 -0.1778)
							(mid 0.249642 -0.249642)
							(end 0.1778 -0.2794)
						)
					)
					(width 0)
					(fill yes)
				)
			)
		)
	)
	(footprint ""
		(layer "F.Cu")
		(at 20.828 -154.051 90)
		(property "Reference" "R8007"
			(at 0 0 90)
			(layer "F.SilkS")
			(hide yes)
			(effects
				(font
					(size 1.27 1.27)
				)
			)
		)
		(property "Value" "0R2J-2-GP"
			(at 0.064008 -3.993896 90)
			(unlocked yes)
			(layer "F.Fab")
			(hide yes)
			(effects
				(font
					(size 1.016 1.016)
					(thickness 0.1524)
				)
			)
		)
		(property "Device Type" "R402H16"
			(at 0.064008 -5.517896 90)
			(unlocked yes)
			(layer "F.Fab")
			(hide yes)
			(effects
				(font
					(size 1.016 1.016)
					(thickness 0.1524)
				)
			)
		)
		(duplicate_pad_numbers_are_jumpers no)
		(fp_line
			(start 0.508 -0.9398)
			(end -0.508 -0.9398)
			(stroke
				(width 0.1524)
				(type default)
			)
			(layer "F.SilkS")
		)
		(fp_line
			(start -0.508 -0.9398)
			(end -0.508 0.9398)
			(stroke
				(width 0.1524)
				(type default)
			)
			(layer "F.SilkS")
		)
		(fp_rect
			(start -0.508 0.9398)
			(end 0.508 -0.9398)
			(stroke
				(width 0)
				(type default)
			)
			(fill no)
			(layer "F.CrtYd")
		)
		(fp_rect
			(start -0.508 0.9398)
			(end 0.508 -0.9398)
			(stroke
				(width 0)
				(type default)
			)
			(fill no)
			(layer "F.Fab")
		)
		(pad "1" smd custom
			(at 0 -0.4445 90)
			(size 0.1397 0.1397)
			(layers "F.Cu" "F.Mask" "F.Paste")
			(net "FM_BMC_RESET_Q36")
			(options
				(clearance outline)
				(anchor circle)
			)
			(primitives
				(gr_poly
					(pts
						(arc
							(start -0.1778 -0.2794)
							(mid -0.249642 -0.249642)
							(end -0.2794 -0.1778)
						)
						(arc
							(start -0.2794 0.1778)
							(mid -0.249642 0.249642)
							(end -0.1778 0.2794)
						)
						(arc
							(start 0.1778 0.2794)
							(mid 0.249642 0.249642)
							(end 0.2794 0.1778)
						)
						(arc
							(start 0.2794 -0.1778)
							(mid 0.249642 -0.249642)
							(end 0.1778 -0.2794)
						)
					)
					(width 0)
					(fill yes)
				)
			)
		)
		(pad "2" smd custom
			(at 0 0.4445 90)
			(size 0.1397 0.1397)
			(layers "F.Cu" "F.Mask" "F.Paste")
			(net "FM_BMC_RESET_Q36_R")
			(options
				(clearance outline)
				(anchor circle)
			)
			(primitives
				(gr_poly
					(pts
						(arc
							(start -0.1778 -0.2794)
							(mid -0.249642 -0.249642)
							(end -0.2794 -0.1778)
						)
						(arc
							(start -0.2794 0.1778)
							(mid -0.249642 0.249642)
							(end -0.1778 0.2794)
						)
						(arc
							(start 0.1778 0.2794)
							(mid 0.249642 0.249642)
							(end 0.2794 0.1778)
						)
						(arc
							(start 0.2794 -0.1778)
							(mid 0.249642 -0.249642)
							(end 0.1778 -0.2794)
						)
					)
					(width 0)
					(fill yes)
				)
			)
		)
	)
	(footprint ""
		(layer "F.Cu")
		(at 319.405 -99.568 180)
		(property "Reference" "C3702"
			(at 0 0 180)
			(layer "F.SilkS")
			(hide yes)
			(effects
				(font
					(size 1.27 1.27)
				)
			)
		)
		(property "Value" "SCD047U25V2KX-GP"
			(at 1.1811 -2.7051 180)
			(unlocked yes)
			(layer "F.Fab")
			(hide yes)
			(effects
				(font
					(size 1.016 1.016)
					(thickness 0.1524)
				)
			)
		)
		(property "Device Type" "C402H22"
			(at 1.1811 -4.2291 180)
			(unlocked yes)
			(layer "F.Fab")
			(hide yes)
			(effects
				(font
					(size 1.016 1.016)
					(thickness 0.1524)
				)
			)
		)
		(duplicate_pad_numbers_are_jumpers no)
		(fp_rect
			(start -0.4318 0.9525)
			(end 0.4318 -0.9525)
			(stroke
				(width 0)
				(type default)
			)
			(fill no)
			(layer "F.CrtYd")
		)
		(fp_rect
			(start -0.4318 0.9525)
			(end 0.4318 -0.9525)
			(stroke
				(width 0)
				(type default)
			)
			(fill no)
			(layer "F.Fab")
		)
		(pad "1" smd custom
			(at 0 -0.4445 180)
			(size 0.1524 0.1524)
			(layers "F.Cu" "F.Mask" "F.Paste")
			(net "P3V3_STBY")
			(options
				(clearance outline)
				(anchor circle)
			)
			(primitives
				(gr_poly
					(pts
						(arc
							(start 0.3048 -0.2032)
							(mid 0.275042 -0.275042)
							(end 0.2032 -0.3048)
						)
						(arc
							(start -0.2032 -0.3048)
							(mid -0.275042 -0.275042)
							(end -0.3048 -0.2032)
						)
						(arc
							(start -0.3048 0.2032)
							(mid -0.275042 0.275042)
							(end -0.2032 0.3048)
						)
						(arc
							(start 0.2032 0.3048)
							(mid 0.275042 0.275042)
							(end 0.3048 0.2032)
						)
					)
					(width 0)
					(fill yes)
				)
			)
		)
		(pad "2" smd custom
			(at 0 0.4445 180)
			(size 0.1524 0.1524)
			(layers "F.Cu" "F.Mask" "F.Paste")
			(net "GND")
			(options
				(clearance outline)
				(anchor circle)
			)
			(primitives
				(gr_poly
					(pts
						(arc
							(start 0.3048 -0.2032)
							(mid 0.275042 -0.275042)
							(end 0.2032 -0.3048)
						)
						(arc
							(start -0.2032 -0.3048)
							(mid -0.275042 -0.275042)
							(end -0.3048 -0.2032)
						)
						(arc
							(start -0.3048 0.2032)
							(mid -0.275042 0.275042)
							(end -0.2032 0.3048)
						)
						(arc
							(start 0.2032 0.3048)
							(mid 0.275042 0.275042)
							(end 0.3048 0.2032)
						)
					)
					(width 0)
					(fill yes)
				)
			)
		)
	)
	(footprint ""
		(layer "F.Cu")
		(at 28.939236 -112.0521 -90)
		(property "Reference" "R709"
			(at 0 0 270)
			(layer "F.SilkS")
			(hide yes)
			(effects
				(font
					(size 1.27 1.27)
				)
			)
		)
		(property "Value" "10KR2F-2-GP"
			(at 0.064008 -3.993896 270)
			(unlocked yes)
			(layer "F.Fab")
			(hide yes)
			(effects
				(font
					(size 1.016 1.016)
					(thickness 0.1524)
				)
			)
		)
		(property "Device Type" "R402H16"
			(at 0.064008 -5.517896 270)
			(unlocked yes)
			(layer "F.Fab")
			(hide yes)
			(effects
				(font
					(size 1.016 1.016)
					(thickness 0.1524)
				)
			)
		)
		(duplicate_pad_numbers_are_jumpers no)
		(fp_line
			(start -0.508 -0.9398)
			(end -0.508 0.9398)
			(stroke
				(width 0.1524)
				(type default)
			)
			(layer "F.SilkS")
		)
		(fp_line
			(start 0.508 -0.9398)
			(end -0.508 -0.9398)
			(stroke
				(width 0.1524)
				(type default)
			)
			(layer "F.SilkS")
		)
		(fp_rect
			(start -0.508 0.9398)
			(end 0.508 -0.9398)
			(stroke
				(width 0)
				(type default)
			)
			(fill no)
			(layer "F.CrtYd")
		)
		(fp_rect
			(start -0.508 0.9398)
			(end 0.508 -0.9398)
			(stroke
				(width 0)
				(type default)
			)
			(fill no)
			(layer "F.Fab")
		)
		(pad "1" smd custom
			(at 0 -0.4445 270)
			(size 0.1397 0.1397)
			(layers "F.Cu" "F.Mask" "F.Paste")
			(net "P3V3_STBY")
			(options
				(clearance outline)
				(anchor circle)
			)
			(primitives
				(gr_poly
					(pts
						(arc
							(start -0.1778 -0.2794)
							(mid -0.249642 -0.249642)
							(end -0.2794 -0.1778)
						)
						(arc
							(start -0.2794 0.1778)
							(mid -0.249642 0.249642)
							(end -0.1778 0.2794)
						)
						(arc
							(start 0.1778 0.2794)
							(mid 0.249642 0.249642)
							(end 0.2794 0.1778)
						)
						(arc
							(start 0.2794 -0.1778)
							(mid 0.249642 -0.249642)
							(end 0.1778 -0.2794)
						)
					)
					(width 0)
					(fill yes)
				)
			)
		)
		(pad "2" smd custom
			(at 0 0.4445 270)
			(size 0.1397 0.1397)
			(layers "F.Cu" "F.Mask" "F.Paste")
			(net "LAN_SMB_ALERT_N")
			(options
				(clearance outline)
				(anchor circle)
			)
			(primitives
				(gr_poly
					(pts
						(arc
							(start -0.1778 -0.2794)
							(mid -0.249642 -0.249642)
							(end -0.2794 -0.1778)
						)
						(arc
							(start -0.2794 0.1778)
							(mid -0.249642 0.249642)
							(end -0.1778 0.2794)
						)
						(arc
							(start 0.1778 0.2794)
							(mid 0.249642 0.249642)
							(end 0.2794 0.1778)
						)
						(arc
							(start 0.2794 -0.1778)
							(mid 0.249642 -0.249642)
							(end 0.1778 -0.2794)
						)
					)
					(width 0)
					(fill yes)
				)
			)
		)
	)
	(footprint ""
		(layer "F.Cu")
		(at 294.207946 -212.420454 180)
		(property "Reference" "C78"
			(at 0 0 180)
			(layer "F.SilkS")
			(hide yes)
			(effects
				(font
					(size 1.27 1.27)
				)
			)
		)
		(property "Value" "SCD22U10V2KX-1GP"
			(at 1.1811 -2.7051 180)
			(unlocked yes)
			(layer "F.Fab")
			(hide yes)
			(effects
				(font
					(size 1.016 1.016)
					(thickness 0.1524)
				)
			)
		)
		(property "Device Type" "C402H22"
			(at 1.1811 -4.2291 180)
			(unlocked yes)
			(layer "F.Fab")
			(hide yes)
			(effects
				(font
					(size 1.016 1.016)
					(thickness 0.1524)
				)
			)
		)
		(duplicate_pad_numbers_are_jumpers no)
		(fp_rect
			(start -0.4318 0.9525)
			(end 0.4318 -0.9525)
			(stroke
				(width 0)
				(type default)
			)
			(fill no)
			(layer "F.CrtYd")
		)
		(fp_rect
			(start -0.4318 0.9525)
			(end 0.4318 -0.9525)
			(stroke
				(width 0)
				(type default)
			)
			(fill no)
			(layer "F.Fab")
		)
		(pad "1" smd custom
			(at 0 -0.4445 180)
			(size 0.1524 0.1524)
			(layers "F.Cu" "F.Mask" "F.Paste")
			(net "PCIE_TX_CAP_N28")
			(options
				(clearance outline)
				(anchor circle)
			)
			(primitives
				(gr_poly
					(pts
						(arc
							(start 0.3048 -0.2032)
							(mid 0.275042 -0.275042)
							(end 0.2032 -0.3048)
						)
						(arc
							(start -0.2032 -0.3048)
							(mid -0.275042 -0.275042)
							(end -0.3048 -0.2032)
						)
						(arc
							(start -0.3048 0.2032)
							(mid -0.275042 0.275042)
							(end -0.2032 0.3048)
						)
						(arc
							(start 0.2032 0.3048)
							(mid 0.275042 0.275042)
							(end 0.3048 0.2032)
						)
					)
					(width 0)
					(fill yes)
				)
			)
		)
		(pad "2" smd custom
			(at 0 0.4445 180)
			(size 0.1524 0.1524)
			(layers "F.Cu" "F.Mask" "F.Paste")
			(net "PCIE_TX_N28")
			(options
				(clearance outline)
				(anchor circle)
			)
			(primitives
				(gr_poly
					(pts
						(arc
							(start 0.3048 -0.2032)
							(mid 0.275042 -0.275042)
							(end 0.2032 -0.3048)
						)
						(arc
							(start -0.2032 -0.3048)
							(mid -0.275042 -0.275042)
							(end -0.3048 -0.2032)
						)
						(arc
							(start -0.3048 0.2032)
							(mid -0.275042 0.275042)
							(end -0.2032 0.3048)
						)
						(arc
							(start 0.2032 0.3048)
							(mid 0.275042 0.275042)
							(end 0.3048 0.2032)
						)
					)
					(width 0)
					(fill yes)
				)
			)
		)
	)
	(footprint ""
		(layer "F.Cu")
		(at 144.0688 -41.402 180)
		(property "Reference" "R769"
			(at 0 0 180)
			(layer "F.SilkS")
			(hide yes)
			(effects
				(font
					(size 1.27 1.27)
				)
			)
		)
		(property "Value" "4K7R2F-GP"
			(at 0.064008 -3.993896 180)
			(unlocked yes)
			(layer "F.Fab")
			(hide yes)
			(effects
				(font
					(size 1.016 1.016)
					(thickness 0.1524)
				)
			)
		)
		(property "Device Type" "R402H16"
			(at 0.064008 -5.517896 180)
			(unlocked yes)
			(layer "F.Fab")
			(hide yes)
			(effects
				(font
					(size 1.016 1.016)
					(thickness 0.1524)
				)
			)
		)
		(duplicate_pad_numbers_are_jumpers no)
		(fp_line
			(start 0.508 -0.9398)
			(end -0.508 -0.9398)
			(stroke
				(width 0.1524)
				(type default)
			)
			(layer "F.SilkS")
		)
		(fp_line
			(start -0.508 -0.9398)
			(end -0.508 0.9398)
			(stroke
				(width 0.1524)
				(type default)
			)
			(layer "F.SilkS")
		)
		(fp_rect
			(start -0.508 0.9398)
			(end 0.508 -0.9398)
			(stroke
				(width 0)
				(type default)
			)
			(fill no)
			(layer "F.CrtYd")
		)
		(fp_rect
			(start -0.508 0.9398)
			(end 0.508 -0.9398)
			(stroke
				(width 0)
				(type default)
			)
			(fill no)
			(layer "F.Fab")
		)
		(pad "1" smd custom
			(at 0 -0.4445 180)
			(size 0.1397 0.1397)
			(layers "F.Cu" "F.Mask" "F.Paste")
			(net "DUT_VDDO")
			(options
				(clearance outline)
				(anchor circle)
			)
			(primitives
				(gr_poly
					(pts
						(arc
							(start -0.1778 -0.2794)
							(mid -0.249642 -0.249642)
							(end -0.2794 -0.1778)
						)
						(arc
							(start -0.2794 0.1778)
							(mid -0.249642 0.249642)
							(end -0.1778 0.2794)
						)
						(arc
							(start 0.1778 0.2794)
							(mid 0.249642 0.249642)
							(end 0.2794 0.1778)
						)
						(arc
							(start 0.2794 -0.1778)
							(mid 0.249642 -0.249642)
							(end 0.1778 -0.2794)
						)
					)
					(width 0)
					(fill yes)
				)
			)
		)
		(pad "2" smd custom
			(at 0 0.4445 180)
			(size 0.1397 0.1397)
			(layers "F.Cu" "F.Mask" "F.Paste")
			(net "EJTAG_TCK")
			(options
				(clearance outline)
				(anchor circle)
			)
			(primitives
				(gr_poly
					(pts
						(arc
							(start -0.1778 -0.2794)
							(mid -0.249642 -0.249642)
							(end -0.2794 -0.1778)
						)
						(arc
							(start -0.2794 0.1778)
							(mid -0.249642 0.249642)
							(end -0.1778 0.2794)
						)
						(arc
							(start 0.1778 0.2794)
							(mid 0.249642 0.249642)
							(end 0.2794 0.1778)
						)
						(arc
							(start 0.2794 -0.1778)
							(mid 0.249642 -0.249642)
							(end 0.1778 -0.2794)
						)
					)
					(width 0)
					(fill yes)
				)
			)
		)
	)
)
